# S9S_MB_2U (Grand Teton) — schematic netlist excerpt (pin names and nets, part order shuffled) for the footprints in the layout excerpt that follows; sources: Cadence DE-HDL packaged netlist, KiCad conversion of 03242023_DA0F0TMBIJ0_F0T_Motherboard_J_brd_V01_OCP.brd

R2317  Q_RES  10K 1% CHIP  pkg 0402LF  page 191 : A = P3V3_E1S_0 ; B = PU_E1S_0_DUALPORT_EN_N
R2935  Q_RES  4.7K 5% CHIP  pkg 0402LF  page 148 : A = P3V3_AUX ; B = FM_GPU_PWRGD_ISO

(kicad_pcb
	(version 20260206)
	(generator "pcbnew")
	(generator_version "10.0")
	(general
		(thickness 1.6)
		(legacy_teardrops no)
	)
	(paper "A4")
	(title_block
		(title "03242023_DA0F0TMBIJ0_F0T_Motherboard_J_brd_V01_OCP.brd")
		(comment 1 "Grand Teton / footprints 3858-3859 of 6105")
	)
	(layers
		(0 "F.Cu" signal "TOP")
		(4 "In1.Cu" signal "GND")
		(6 "In2.Cu" signal "IN1")
		(8 "In3.Cu" signal "GND1")
		(10 "In4.Cu" signal "IN2")
		(12 "In5.Cu" signal "GND2")
		(14 "In6.Cu" signal "IN3")
		(16 "In7.Cu" signal "GND3")
		(18 "In8.Cu" signal "VCC")
		(20 "In9.Cu" signal "VCC1")
		(22 "In10.Cu" signal "GND4")
		(24 "In11.Cu" signal "IN4")
		(26 "In12.Cu" signal "GND5")
		(28 "In13.Cu" signal "IN5")
		(30 "In14.Cu" signal "GND6")
		(32 "In15.Cu" signal "IN6")
		(34 "In16.Cu" signal "GND7")
		(2 "B.Cu" signal "BOTTOM")
		(9 "F.Adhes" user "F.Adhesive")
		(11 "B.Adhes" user "B.Adhesive")
		(13 "F.Paste" user "Package Geometry/Pastemask Top")
		(15 "B.Paste" user "Package Geometry/Pastemask Bottom")
		(5 "F.SilkS" user "Ref Des/Silkscreen Top")
		(7 "B.SilkS" user "Ref Des/Silkscreen Bottom")
		(1 "F.Mask" user "Board Geometry/Soldermask Top")
		(3 "B.Mask" user "Board Geometry/Soldermask Bottom")
		(17 "Dwgs.User" user "User.Drawings")
		(19 "Cmts.User" user "User.Comments")
		(21 "Eco1.User" user "User.Eco1")
		(23 "Eco2.User" user "User.Eco2")
		(25 "Edge.Cuts" user "Board Geometry/Outline")
		(27 "Margin" user)
		(31 "F.CrtYd" user "Package Geometry/Place Bound Top")
		(29 "B.CrtYd" user "Package Geometry/Place Bound Bottom")
		(35 "F.Fab" user "Ref Des/Assembly Top")
		(33 "B.Fab" user "Ref Des/Assembly Bottom")
	)
	(footprint ""
		(layer "F.Cu")
		(at 240.00841 -46.967648 180)
		(property "Reference" "R2317"
			(at 0 0 180)
			(layer "F.SilkS")
			(hide yes)
			(effects
				(font
					(size 1.27 1.27)
				)
			)
		)
		(property "Value" ""
			(at 0 0 180)
			(layer "F.Fab")
			(effects
				(font
					(size 1.27 1.27)
				)
			)
		)
		(duplicate_pad_numbers_are_jumpers no)
		(fp_line
			(start 0.7874 0.4064)
			(end -0.7874 0.4064)
			(stroke
				(width 0.1524)
				(type default)
			)
			(layer "F.SilkS")
		)
		(fp_line
			(start 0.7874 -0.4064)
			(end 0.7874 0.4064)
			(stroke
				(width 0.1524)
				(type default)
			)
			(layer "F.SilkS")
		)
		(fp_line
			(start -0.7874 0.4064)
			(end -0.7874 -0.4064)
			(stroke
				(width 0.1524)
				(type default)
			)
			(layer "F.SilkS")
		)
		(fp_line
			(start -0.7874 -0.4064)
			(end 0.7874 -0.4064)
			(stroke
				(width 0.1524)
				(type default)
			)
			(layer "F.SilkS")
		)
		(fp_line
			(start 0.67945 0.3048)
			(end 0.120396 0.3048)
			(stroke
				(width 0.1)
				(type default)
			)
			(layer "F.Fab")
		)
		(fp_line
			(start 0.67945 -0.3048)
			(end 0.67945 0.3048)
			(stroke
				(width 0.1)
				(type default)
			)
			(layer "F.Fab")
		)
		(fp_line
			(start 0.12065 -0.2794)
			(end 0.12065 -0.3048)
			(stroke
				(width 0.1)
				(type default)
			)
			(layer "F.Fab")
		)
		(fp_line
			(start 0.12065 -0.3048)
			(end 0.67945 -0.3048)
			(stroke
				(width 0.1)
				(type default)
			)
			(layer "F.Fab")
		)
		(fp_line
			(start 0.120396 0.3048)
			(end 0.120396 0.2794)
			(stroke
				(width 0.1)
				(type default)
			)
			(layer "F.Fab")
		)
		(fp_line
			(start 0.120396 0.2794)
			(end -0.12065 0.2794)
			(stroke
				(width 0.1)
				(type default)
			)
			(layer "F.Fab")
		)
		(fp_line
			(start -0.12065 0.3048)
			(end -0.67945 0.3048)
			(stroke
				(width 0.1)
				(type default)
			)
			(layer "F.Fab")
		)
		(fp_line
			(start -0.12065 0.2794)
			(end -0.12065 0.3048)
			(stroke
				(width 0.1)
				(type default)
			)
			(layer "F.Fab")
		)
		(fp_line
			(start -0.12065 -0.2794)
			(end 0.12065 -0.2794)
			(stroke
				(width 0.1)
				(type default)
			)
			(layer "F.Fab")
		)
		(fp_line
			(start -0.12065 -0.305054)
			(end -0.12065 -0.2794)
			(stroke
				(width 0.1)
				(type default)
			)
			(layer "F.Fab")
		)
		(fp_line
			(start -0.67945 0.3048)
			(end -0.67945 -0.305054)
			(stroke
				(width 0.1)
				(type default)
			)
			(layer "F.Fab")
		)
		(fp_line
			(start -0.67945 -0.305054)
			(end -0.12065 -0.305054)
			(stroke
				(width 0.1)
				(type default)
			)
			(layer "F.Fab")
		)
		(pad "1" smd circle
			(at -0.40005 0 180)
			(size 0 0)
			(layers "F.Cu" "F.Mask" "F.Paste")
			(net "P3V3_E1S_0")
		)
		(pad "2" smd circle
			(at 0.40005 0 180)
			(size 0 0)
			(layers "F.Cu" "F.Mask" "F.Paste")
			(net "PU_E1S_0_DUALPORT_EN_N")
		)
	)
	(footprint ""
		(layer "F.Cu")
		(at 24.046942 -414.111948)
		(property "Reference" "R2935"
			(at 0 0 0)
			(layer "F.SilkS")
			(hide yes)
			(effects
				(font
					(size 1.27 1.27)
				)
			)
		)
		(property "Value" ""
			(at 0 0 0)
			(layer "F.Fab")
			(effects
				(font
					(size 1.27 1.27)
				)
			)
		)
		(duplicate_pad_numbers_are_jumpers no)
		(fp_line
			(start -0.7874 -0.4064)
			(end 0.7874 -0.4064)
			(stroke
				(width 0.1524)
				(type default)
			)
			(layer "F.SilkS")
		)
		(fp_line
			(start -0.7874 0.4064)
			(end -0.7874 -0.4064)
			(stroke
				(width 0.1524)
				(type default)
			)
			(layer "F.SilkS")
		)
		(fp_line
			(start 0.7874 -0.4064)
			(end 0.7874 0.4064)
			(stroke
				(width 0.1524)
				(type default)
			)
			(layer "F.SilkS")
		)
		(fp_line
			(start 0.7874 0.4064)
			(end -0.7874 0.4064)
			(stroke
				(width 0.1524)
				(type default)
			)
			(layer "F.SilkS")
		)
		(fp_line
			(start -0.67945 -0.305054)
			(end -0.12065 -0.305054)
			(stroke
				(width 0.1)
				(type default)
			)
			(layer "F.Fab")
		)
		(fp_line
			(start -0.67945 0.3048)
			(end -0.67945 -0.305054)
			(stroke
				(width 0.1)
				(type default)
			)
			(layer "F.Fab")
		)
		(fp_line
			(start -0.12065 -0.305054)
			(end -0.12065 -0.2794)
			(stroke
				(width 0.1)
				(type default)
			)
			(layer "F.Fab")
		)
		(fp_line
			(start -0.12065 -0.2794)
			(end 0.12065 -0.2794)
			(stroke
				(width 0.1)
				(type default)
			)
			(layer "F.Fab")
		)
		(fp_line
			(start -0.12065 0.2794)
			(end -0.12065 0.3048)
			(stroke
				(width 0.1)
				(type default)
			)
			(layer "F.Fab")
		)
		(fp_line
			(start -0.12065 0.3048)
			(end -0.67945 0.3048)
			(stroke
				(width 0.1)
				(type default)
			)
			(layer "F.Fab")
		)
		(fp_line
			(start 0.120396 0.2794)
			(end -0.12065 0.2794)
			(stroke
				(width 0.1)
				(type default)
			)
			(layer "F.Fab")
		)
		(fp_line
			(start 0.120396 0.3048)
			(end 0.120396 0.2794)
			(stroke
				(width 0.1)
				(type default)
			)
			(layer "F.Fab")
		)
		(fp_line
			(start 0.12065 -0.3048)
			(end 0.67945 -0.3048)
			(stroke
				(width 0.1)
				(type default)
			)
			(layer "F.Fab")
		)
		(fp_line
			(start 0.12065 -0.2794)
			(end 0.12065 -0.3048)
			(stroke
				(width 0.1)
				(type default)
			)
			(layer "F.Fab")
		)
		(fp_line
			(start 0.67945 -0.3048)
			(end 0.67945 0.3048)
			(stroke
				(width 0.1)
				(type default)
			)
			(layer "F.Fab")
		)
		(fp_line
			(start 0.67945 0.3048)
			(end 0.120396 0.3048)
			(stroke
				(width 0.1)
				(type default)
			)
			(layer "F.Fab")
		)
		(pad "1" smd circle
			(at -0.40005 0)
			(size 0 0)
			(layers "F.Cu" "F.Mask" "F.Paste")
			(net "P3V3_AUX")
		)
		(pad "2" smd circle
			(at 0.40005 0)
			(size 0 0)
			(layers "F.Cu" "F.Mask" "F.Paste")
			(net "FM_GPU_PWRGD_ISO")
		)
	)
)
